FILE_TYPE = CONNECTIVITY;
{Allegro Design Entry HDL 17.2-2016 S081 (4005846) 1/11/2022}
"PAGE_NUMBER" = 227;
0"NC";
1"PVNN_TERM_CPU0\g";
2"P12V_SCM\g";
3"P12V_SCM\g";
4"GND\g";
5"GND\g";
6"GND\g";
7"GND\g";
8"GND\g";
9"SMB_HOST_3V3AUX_SCL";
10"SMB_SML1_PMBUS_3V3AUX_PCH_SCL";
11"SMB_PCIE2_3V3AUX_SDA_R0";
12"SMB_PCIE3_3V3AUX_SCL_R";
13"SMB_S3M_CPU_3V3AUX_SDA_R0";
14"FM_BMC_PWRBTN_OUT_R_N"CDS_PHYS_NET_NAME"FM_BMC_PWRBTN_OUT_R_N";
15"FM_UARTSW_MSB_R";
16"FM_UARTSW_LSB_R";
17"FM_SCM_PRSNT1_N";
18"IRQ0_A57";
19"FM_BMC_INTRUDER_N";
20"ROT_P1_RST_IND_N";
21"FM_JTAG_BMC_MUX_SEL_FROM_BMC_R2";
22"SMB_1_PLD_3V3AUX_SCL";
23"SMB_SML0_3V3AUX_SDA_R1";
24"USB3_PCH_RX_DN<4>";
25"TP_PCIE_HPM_RXN[1]";
26"CLK_100M_BMC_RC_DP";
27"USB3_PCH_TX_BUF_C_DN<4>";
28"USB3_PCH_TX_BUF_C_DP<4>";
29"USB2_HUB_2_BUF_EXT_DN";
30"USB2_HUB_2_BUF_EXT_DP";
31"USB2_8_DP";
32"SMB_HOST_3V3AUX_SCL_R0";
33"SMB_OCP_SFF_3V3AUX_SDA_R0";
34"FM_SOL_UART_CH_SEL";
35"USB2_7_DN"CDS_PHYS_NET_NAME"USB2_7_DN";
36"USB2_7_DP"CDS_PHYS_NET_NAME"USB2_7_DP";
37"PRSNT0_N";
38"CLK_50M_RMII_BMC_OCP"CDS_PHYS_NET_NAME"CLK_50M_RMII_BMC_OCP";
39"RMII_BMC_OCP_TX_EN"CDS_PHYS_NET_NAME"RMII_BMC_OCP_TX_EN";
40"PECI_BMC";
41"PVCCIO_PECI_BMC";
42"RMII_OCP_BMC_RXD_1";
43"RMII_BMC_OCP_RX_ER"CDS_PHYS_NET_NAME"RMII_BMC_OCP_RX_ER";
44"RMII_BMC_OCP_TXD_1";
45"RMII_BMC_OCP_TXD_0";
46"SGPIO_DO_0";
47"SGPIO_DI_0";
48"SGPIO_CLK_0";
49"ESPI_HOST_LPC_BMC_LFRAME_N";
50"H_CPU_CATERR_LVC2_BMC_N"CDS_PHYS_NET_NAME"H_CPU_CATERR_LVC2_BMC_N";
51"SPI_TPM_CS_N"CDS_PHYS_NET_NAME"SPI_TPM_CS_N";
52"ESPI_HOST_LPC_BMC_CLK";
53"UART_BMC_BIC_TX"CDS_PHYS_NET_NAME"UART_BMC_BIC_TX";
54"UART_BMC_BIC_BUF_RX"CDS_PHYS_NET_NAME"UART_BMC_BIC_BUF_RX";
55"USB2_7_R_DP"CDS_PHYS_NET_NAME"USB2_7_R_DP";
56"SPI_SYS_WP_IO2";
57"SPI_SYS_MISO";
58"SPI_SYS_MOSI";
59"SPI_SYS_CS0_N";
60"SPI_SYS_CLK";
61"ESPI_LPC_LAD0_IO3";
62"ESPI_LPC_LAD0_IO2";
63"ESPI_LPC_LAD0_IO0";
64"ESPI_BMC_LPC_RST_N";
65"RST_SRST_PLD_BMC_N"CDS_PHYS_NET_NAME"RST_SRST_PLD_BMC_N";
66"RMII_OCP_BMC_CRSDV"CDS_PHYS_NET_NAME"RMII_OCP_BMC_CRSDV";
67"SPI_SYS_HOLD_IO3";
68"FM_LPC_ESPI_SEL";
69"ESPI_LPC_LAD0_IO1";
70"IRQ_ESPI_LPC_SERIRQ_ALERT_R_N";
71"USB2_7_R_DN"CDS_PHYS_NET_NAME"USB2_7_R_DN";
72"FM_SOL_UART_CH_SEL_R";
73"SGPIO_DI_1";
74"SGPIO_CLK_1";
75"SGPIO_DO_1"CDS_PHYS_NET_NAME"SGPIO_DO_1";
76"SGPIO_LD_0";
77"RMII_OCP_BMC_RXD_0";
78"I3C_SPD_DDREFGH_CPU1_BMC_R_SCL";
79"I3C_SPD_DDREFGH_CPU0_BMC_R_SCL";
80"I3C_SPD_DDRABCD_CPU0_BMC_R_SDA"CDS_PHYS_NET_NAME"I3C_SPD_DDRABCD_CPU0_BMC_R_SDA";
81"I3C_SPD_DDRABCD_CPU0_BMC_R_SCL"CDS_PHYS_NET_NAME"I3C_SPD_DDRABCD_CPU0_BMC_R_SCL";
82"I3C_SPD_DDREFGH_CPU1_BMC_R_SDA";
83"I3C_SPD_DDRABCD_CPU1_BMC_R_SDA";
84"I3C_SPD_DDREFGH_CPU0_BMC_R_SDA";
85"I3C_SPD_DDRABCD_CPU1_BMC_R_SCL";
86"SMB_HOST_3V3AUX_SDA_R0";
87"SMB_VR_3V3AUX_SCL_R0";
88"SMB_VR_3V3AUX_SDA_R0";
89"SMB_SML1_PMBUS_3V3AUX_PCH_SCL_R0";
90"SMB_SML1_PMBUS_3V3AUX_PCH_SDA_R0";
91"I3C_BMC_SWB_SCL";
92"I3C_BMC_SWB_SDA";
93"SMB_OCP_V3_2_3V3AUX_SCL_R0";
94"CLK_100M_BMC_P3E_DP_R";
95"P3E_PCH_BMC_RX_DP";
96"P3E_PCH_BMC_RX_DN";
97"SMB_PCIE0_3V3AUX_SCL";
98"JTAG_BMC_TCK";
99"P3E_PCH_BMC_TX_C_DP";
100"P3E_PCH_BMC_TX_C_DN";
101"CLK_100M_BMC_P3E_DN_R";
102"SMB_OCP_V3_2_3V3AUX_SDA_R0";
103"SMB_PCIE0_3V3AUX_SDA";
104"SMB_SML0_3V3AUX_SCL_R1";
105"SMB_1_PLD_3V3AUX_SCL_R3";
106"JTAG_BMC_TDI";
107"SMB_1_PLD_3V3AUX_SDA_R3";
108"VIRTUAL_RESEAT";
109"SMB_OCP_SFF_3V3AUX_SCL_R0";
110"SMB_FAN_3V3AUX_SCL";
111"SMB_FAN_3V3AUX_SDA";
112"JTAG_BMC_TMS";
113"SMB_PCIE2_3V3AUX_SCL_R0";
114"SMB_VR_SENSOR_3V3AUX_SDA";
115"SMB_VR_SENSOR_3V3AUX_SCL";
116"SMB_SML0_3V3AUX_SCL";
117"SMB_OCP_V3_2_3V3AUX_SDA";
118"CLK_100M_BMC_P3E_DP";
119"CLK_100M_BMC_P3E_DN";
120"SMB_1_PLD_3V3AUX_SDA";
121"SMB_OCP_V3_2_3V3AUX_SCL";
122"SMB_HOST_3V3AUX_SDA";
123"SMB_OCP_SFF_3V3AUX_SDA";
124"SMB_2_BMC_GPU_SDA";
125"SMB_SML0_3V3AUX_SDA";
126"SMB_SML1_PMBUS_3V3AUX_PCH_SDA";
127"SMB_OCP_SFF_3V3AUX_SCL";
128"SMB_2_BMC_GPU_SCL";
129"PVCCIO_PECI_BMC"CDS_PHYS_NET_NAME"PVCCIO_PECI_BMC";
130"JTAG_BMC_TDO";
131"SGPIO_LD_1";
132"FM_PCH_SPKR";
133"LED_HDD_ACTIVITY_B_N";
134"FM_AC_PWR_BTN_R_N"CDS_PHYS_NET_NAME"FM_AC_PWR_BTN_R_N";
135"P3V_BAT_R";
136"TP_PCIE_HPM_TXN[3]";
137"P2E_MB_BMC_TX_C_DN<0>";
138"TP_PCIE_HPM_TXP[3]";
139"P2E_MB_BMC_TX_C_DP<0>";
140"TP_PCIE_HPM_TXP[1]"CDS_PHYS_NET_NAME"TP_PCIE_HPM_TXP<1>";
141"TP_PCIE_HPM_TXN[1]"CDS_PHYS_NET_NAME"TP_PCIE_HPM_TXN<1>";
142"USB2_HOST_BMC_B_DP";
143"USB2_HOST_BMC_B_DN";
144"USB2_8_DN";
145"TP_SPI_2_PLD_IO3"CDS_PHYS_NET_NAME"TP_SPI_2_PLD_IO3";
146"RST_SGPIO_RESET_N"CDS_PHYS_NET_NAME"RST_SGPIO_RESET_N";
147"TP_SPI_2_PLD_IO2"CDS_PHYS_NET_NAME"TP_SPI_2_PLD_IO2";
148"TP_SPI_2_PLD_IO1"CDS_PHYS_NET_NAME"TP_SPI_2_PLD_IO1";
149"TP_SPI_2_PLD_IO0"CDS_PHYS_NET_NAME"TP_SPI_2_PLD_IO0";
150"TP_SPI_2_PLD_CS_N"CDS_PHYS_NET_NAME"TP_SPI_2_PLD_CS_N";
151"TP_SPI_2_PLD_CLK"CDS_PHYS_NET_NAME"TP_SPI_2_PLD_CLK";
152"FM_AC_PWR_BTN_N"CDS_PHYS_NET_NAME"FM_AC_PWR_BTN_N";
153"P3V_BAT_R1";
154"IRQ_SGPIO_INTR_N"CDS_PHYS_NET_NAME"IRQ_SGPIO_INTR_N";
155"TP_PCIE_HPM_RXP[1]";
156"P2E_MB_BMC_RX_BUF_DP<0>";
157"SMB_S3M_CPU_3V3AUX_SCL_R0";
158"SMB_PCIE3_3V3AUX_SDA_R";
159"P2E_MB_BMC_RX_BUF_DN<0>";
160"RST_PLTRST_B_N";
161"PWRGD_SYS_PWROK"CDS_PHYS_NET_NAME"PWRGD_SYS_PWROK";
162"USB3_PCH_RX_DP<4>";
163"CLK_100M_BMC_RC_DN";
164"PWRGD_PS_PWROK_R"CDS_PHYS_NET_NAME"PWRGD_PS_PWROK_R";
165"TP_HPM_STBY_EN"CDS_PHYS_NET_NAME"TP_HPM_STBY_EN";
166"RST_MB_STBY_N"CDS_PHYS_NET_NAME"RST_MB_STBY_N";
167"JTAG_BMC_DBP_PREQ_N"CDS_PHYS_NET_NAME"JTAG_BMC_DBP_PREQ_N";
168"JTAG_DBP_BMC_PRDY_N"CDS_PHYS_NET_NAME"JTAG_DBP_BMC_PRDY_N";
169"SMB_S3M_CPU_3V3AUX_SDA";
170"FM_JTAG_BMC_MUX_SEL_FROM_BMC_R";
171"SMB_1_BMC_GPU_SCL";
172"SMB_1_BMC_GPU_SDA";
173"SMB_S3M_CPU_3V3AUX_SCL";
174"PWRGD_PS_PWROK"CDS_PHYS_NET_NAME"PWRGD_PS_PWROK";
175"FM_BMC_PWRBTN_OUT_N"CDS_PHYS_NET_NAME"FM_BMC_PWRBTN_OUT_N";
176"FM_UARTSW_MSB_N";
177"ROT_P1_RST_IND_N_R";
178"FM_UARTSW_LSB_N";
179"IRQ_SMI_ACTIVE_BMC_N";
180"FM_BMC_INTRUDER_N"CDS_PHYS_NET_NAME"FM_BMC_INTRUDER_N";
%"UNIVERSAL_GND"
"1","(-14825,-2675)","0","logical_power","I1";
;
CDS_LIB"logical_power"
HDL_POWER"GND";
"A"4;
%"Q_RES"
"1","(-13275,1275)","0","pure_quanta","I100";
;
PART_NUMBER"CS03322FB03"
WATTAGE"1/16W"
VALUE"33.2"
PACK_TYPE"0402LF"
TOLERANCE"1%"
MATERIAL"CHIP"
$LOCATION"R2419"
CDS_LIB"pure_quanta"
CDS_LOCATION"R2419"
$SEC"1"
CDS_SEC"1";
"B"
$PN"2"32;
"A"
$PN"1"9;
%"Q_RES"
"1","(-13275,1375)","0","pure_quanta","I101";
;
PART_NUMBER"CS03322FB03"
VALUE"33.2"
TOLERANCE"1%"
MATERIAL"CHIP"
$LOCATION"R3238"
CDS_LIB"pure_quanta"
WATTAGE"1/16W"
PACK_TYPE"0402LF"
CDS_LOCATION"R3238"
$SEC"1"
CDS_SEC"1";
"B"
$PN"2"109;
"A"
$PN"1"127;
%"Q_RES"
"1","(-13275,1325)","0","pure_quanta","I102";
;
PART_NUMBER"CS03322FB03"
VALUE"33.2"
TOLERANCE"1%"
MATERIAL"CHIP"
$LOCATION"R3239"
CDS_LIB"pure_quanta"
WATTAGE"1/16W"
PACK_TYPE"0402LF"
CDS_LOCATION"R3239"
$SEC"1"
CDS_SEC"1";
"B"
$PN"2"33;
"A"
$PN"1"123;
%"UNIVERSAL_POWER"
"1","(-11275,2450)","0","logical_power","I126";
;
HDL_POWER"P12V_SCM"
CDS_LIB"logical_power";
"A"2;
%"Q_RES"
"1","(-7800,1525)","0","pure_quanta","I159";
;
PART_NUMBER"CS00002JB13"
MATERIAL"CHIP"
VALUE"0"
$LOCATION"R3778"
WATTAGE"1/16W"
TOLERANCE"5%"
PACK_TYPE"0402LF"
CDS_LIB"pure_quanta"
CDS_LOCATION"R3778"
$SEC"1"
CDS_SEC"1";
"B"
$PN"2"34;
"A"
$PN"1"72;
%"UNIVERSAL_POWER"
"1","(-9550,2450)","0","logical_power","I160";
;
HDL_POWER"P12V_SCM"
CDS_LIB"logical_power";
"A"3;
%"Q_RES"
"1","(-8175,1775)","0","pure_quanta","I164";
;
PART_NUMBER"CS00002JB13"
VALUE"0"
TOLERANCE"5%"
MATERIAL"EMPTY"
$LOCATION"R2257"
WATTAGE"1/16W"
PACK_TYPE"0402LF"
CDS_LIB"pure_quanta"
CDS_LOCATION"R2257"
$SEC"1"
CDS_SEC"1";
"B"
$PN"2"35;
"A"
$PN"1"71;
%"Q_RES"
"1","(-8175,1825)","0","pure_quanta","I167";
;
PART_NUMBER"CS00002JB13"
PACK_TYPE"0402LF"
VALUE"0"
TOLERANCE"5%"
MATERIAL"EMPTY"
WATTAGE"1/16W"
$LOCATION"R2256"
CDS_LIB"pure_quanta"
CDS_LOCATION"R2256"
$SEC"1"
CDS_SEC"1";
"B"
$PN"2"36;
"A"
$PN"1"55;
%"UNIVERSAL_GND"
"1","(-7625,2050)","0","logical_power","I171";
;
HDL_POWER"GND"
CDS_LIB"logical_power";
"A"8;
%"Q_RES"
"2","(-7625,2250)","0","pure_quanta","I172";
;
PART_NUMBER"CS00002JB13"
MATERIAL"CHIP"
WATTAGE"1/16W"
PACK_TYPE"0402LF"
VALUE"0"
TOLERANCE"5%"
$LOCATION"R1801"
CDS_LIB"pure_quanta"
CDS_LOCATION"R1801"
$SEC"1"
CDS_SEC"1";
"A"
$PN"1"37;
"B"
$PN"2"8;
%"SCONN168_ME1016810202011"
"1","(-10400,-200)","2","pure_quanta","I173";
;
PART_NUMBER"DFHSG8FR011"
MATERIAL"IO"
PART_TYPE"SMLF"
VALUE"SCONN168_ME1016810202011"
LOCATION"J41"
SEC_TYPE""
CDS_LMAN_SYM_OUTLINE"-500,2475,500,-2475"
NEEDS_NO_SIZE"TRUE"
CDS_LIB"pure_quanta"
SEC"1";
"G5"
$PN"G5"5;
"G4"
$PN"G4"5;
"G3"
$PN"G3"5;
"G2"
$PN"G2"5;
"G1"
$PN"G1"5;
"PRSNTB3# \B"
$PN"B70"6;
"RFU1_NC_B69"
$PN"B69"136;
"RFU1_NC_B68"
$PN"B68"138;
"GND_B67"
$PN"B67"6;
"PETP15"
$PN"B66"137;
"PETN15"
$PN"B65"139;
"GND_B64"
$PN"B64"6;
"PETP14"
$PN"B63"141;
"PETN14"
$PN"B62"140;
"GND_B61"
$PN"B61"6;
"PETP13"
$PN"B60"27;
"PETN13"
$PN"B59"28;
"GND_B58"
$PN"B58"6;
"PETP12"
$PN"B57"29;
"PWRBRK0# \B"
$PN"A70"5;
"USB_DATP"
$PN"A69"163;
"USB_DATN"
$PN"A68"26;
"GND_A67"
$PN"A67"5;
"PERP15"
$PN"A66"159;
"PERN15"
$PN"A65"156;
"GND_A64"
$PN"A64"5;
"PERP14"
$PN"A63"25;
"PERN14"
$PN"A62"155;
"GND_A61"
$PN"A61"5;
"PERP13"
$PN"A60"24;
"PERN13"
$PN"A59"162;
"GND_A58"
$PN"A58"5;
"PERP12"
$PN"A57"17;
"PERN12"
$PN"A56"18;
"GND_A55"
$PN"A55"16;
"PERP11"
$PN"A54"19;
"PERN11"
$PN"A53"20;
"GND_A52"
$PN"A52"15;
"PERP10"
$PN"A51"160;
"PERN10"
$PN"A50"168;
"GND_A49"
$PN"A49"167;
"PERP9"
$PN"A48"161;
"PERN9"
$PN"A47"14;
"GND_A46"
$PN"A46"166;
"PERP8"
$PN"A45"165;
"PERN8"
$PN"A44"164;
"GND_A43"
$PN"A43"21;
"PRSNTB1# \B"
$PN"A42"5;
"GND_A41"
$PN"A41"13;
"PERP7"
$PN"A40"157;
"PERN7"
$PN"A39"158;
"GND_A38"
$PN"A38"12;
"PERP6"
$PN"A37"130;
"PERN6"
$PN"A36"106;
"GND_A35"
$PN"A35"112;
"PERP5"
$PN"A34"98;
"PERN5"
$PN"A33"5;
"GND_A32"
$PN"A32"11;
"PERP4"
$PN"A31"113;
"PERN4"
$PN"A30"111;
"GND_A29"
$PN"A29"110;
"GND_A28"
$PN"A28"107;
"PERP3"
$PN"A27"105;
"PERN3"
$PN"A26"23;
"GND_A25"
$PN"A25"104;
"PERP2"
$PN"A24"103;
"PERN2"
$PN"A23"97;
"GND_A22"
$PN"A22"5;
"PERP1"
$PN"A21"96;
"PERN1"
$PN"A20"95;
"GND_A19"
$PN"A19"5;
"PERP0"
$PN"A18"100;
"PERN0"
$PN"A17"99;
"GND_A16"
$PN"A16"5;
"REFCLKP1"
$PN"A15"101;
"REFCLKN1"
$PN"A14"94;
"GND_A13"
$PN"A13"5;
"PRSNTB2# \B"
$PN"A12"102;
"PERST1# \B"
$PN"A11"93;
"PRSNTA# \B"
$PN"A10"92;
"SMRST# \B"
$PN"A9"91;
"SMDAT"
$PN"A8"90;
"SMCLK"
$PN"A7"89;
"GND_A6"
$PN"A6"88;
"GND_A5"
$PN"A5"87;
"GND_A4"
$PN"A4"86;
"GND_A3"
$PN"A3"32;
"GND_A2"
$PN"A2"33;
"GND_A1"
$PN"A1"109;
"RBT_CLK_IN"
$PN"OA14"108;
"GND_OA13"
$PN"OA13"5;
"REFCLKP3"
$PN"OA12"82;
"REFCLKN3"
$PN"OA11"78;
"GND_OA10"
$PN"OA10"83;
"RBT_TXD0"
$PN"OA9"85;
"RBT_TXD1"
$PN"OA8"84;
"RBT_TX_EN"
$PN"OA7"79;
"SLOT_ID1"
$PN"OA6"80;
"RBT_ARB_OUT"
$PN"OA5"81;
"RBT_ARB_IN"
$PN"OA4"5;
"WAKE# \B"
$PN"OA3"5;
"PERST3# \B"
$PN"OA2"2;
"PERST2# \B"
$PN"OA1"2;
"PETN12"
$PN"B56"30;
"GND_B55"
$PN"B55"6;
"PETP11"
$PN"B54"144;
"PETN11"
$PN"B53"31;
"GND_B52"
$PN"B52"6;
"PETP10"
$PN"B51"143;
"PETN10"
$PN"B50"142;
"GND_B49"
$PN"B49"6;
"PETP9"
$PN"B48"145;
"PETN9"
$PN"B47"147;
"GND_B46"
$PN"B46"148;
"PETP8"
$PN"B45"149;
"PETN8"
$PN"B44"150;
"GND_B43"
$PN"B43"151;
"PRSNTB0# \B"
$PN"B42"152;
"GND_B41"
$PN"B41"153;
"PETP7"
$PN"B40"154;
"PETN7"
$PN"B39"146;
"GND_B38"
$PN"B38"6;
"PETP6"
$PN"B37"131;
"PETN6"
$PN"B36"73;
"GND_B35"
$PN"B35"74;
"PETP5"
$PN"B34"75;
"PETN5"
$PN"B33"6;
"GND_B32"
$PN"B32"76;
"PETP4"
$PN"B31"47;
"PETN4"
$PN"B30"48;
"GND_B29"
$PN"B29"46;
"GND_B28"
$PN"B28"41;
"PETP3"
$PN"B27"40;
"PETN3"
$PN"B26"6;
"GND_B25"
$PN"B25"42;
"PETP2"
$PN"B24"77;
"PETN2"
$PN"B23"43;
"GND_B22"
$PN"B22"44;
"PETP1"
$PN"B21"45;
"PETN1"
$PN"B20"39;
"GND_B19"
$PN"B19"66;
"PETP0"
$PN"B18"38;
"PETN0"
$PN"B17"6;
"GND_B16"
$PN"B16"67;
"REFCLKP0"
$PN"B15"56;
"REFCLKN0"
$PN"B14"57;
"GND_B13"
$PN"B13"58;
"AUX_PWR_EN"
$PN"B12"59;
"+3.3V_EDGE"
$PN"B11"60;
"PERST0# \B"
$PN"B10"6;
"BIF2# \B"
$PN"B9"68;
"BIF1# \B"
$PN"B8"61;
"BIF0# \B"
$PN"B7"62;
"+12V_EDGE_B6"
$PN"B6"69;
"+12V_EDGE_B5"
$PN"B5"63;
"+12V_EDGE_B4"
$PN"B4"64;
"+12V_EDGE_B3"
$PN"B3"70;
"+12V_EDGE_B2"
$PN"B2"49;
"+12V_EDGE_B1"
$PN"B1"52;
"RBT_CRS_DV"
$PN"OB14"72;
"GND_OB13"
$PN"OB13"50;
"REFCLKP2"
$PN"OB12"51;
"REFCLKN2"
$PN"OB11"65;
"GND_OB10"
$PN"OB10"6;
"RBT_RXD0"
$PN"OB9"71;
"RBT_RXD1"
$PN"OB8"55;
"SLOT_ID0"
$PN"OB7"6;
"CLK"
$PN"OB6"54;
"DATA_OUT"
$PN"OB5"53;
"DATA_IN"
$PN"OB4"6;
"LD# \B"
$PN"OB3"37;
"MAIN_PWR_EN"
$PN"OB2"3;
"NIC_PWR_GOOD"
$PN"OB1"3;
%"Q_RES"
"1","(-13325,-1575)","0","pure_quanta","I18";
;
PART_NUMBER"CS00002JB13"
TOLERANCE"5%"
VALUE"0"
MATERIAL"CHIP"
$LOCATION"R506"
WATTAGE"1/16W"
PACK_TYPE"0402LF"
CDS_LIB"pure_quanta"
CDS_LOCATION"R506"
$SEC"1"
CDS_SEC"1";
"B"
$PN"2"18;
"A"
$PN"1"179;
%"Q_RES"
"1","(-13325,-1525)","0","pure_quanta","I19";
;
PART_NUMBER"CS00002JB13"
VALUE"0"
TOLERANCE"5%"
MATERIAL"CHIP"
$LOCATION"R3777"
WATTAGE"1/16W"
PACK_TYPE"0402LF"
CDS_LIB"pure_quanta"
CDS_LOCATION"R3777"
$SEC"1"
CDS_SEC"1";
"B"
$PN"2"16;
"A"
$PN"1"178;
%"Q_RES"
"2","(-14825,-2425)","0","pure_quanta","I2";
;
PART_NUMBER"CS00002JB13"
PACK_TYPE"0402LF"
WATTAGE"1/16W"
MATERIAL"CHIP"
TOLERANCE"5%"
VALUE"0"
$LOCATION"R4809"
CDS_LIB"pure_quanta"
CDS_LOCATION"R4809"
$SEC"1"
CDS_SEC"1";
"A"
$PN"1"180;
"B"
$PN"2"4;
%"Q_RES"
"1","(-13325,-1425)","0","pure_quanta","I20";
;
PART_NUMBER"CS00002JB13"
VALUE"0"
TOLERANCE"5%"
MATERIAL"CHIP"
$LOCATION"R1798"
PACK_TYPE"0402LF"
WATTAGE"1/16W"
CDS_LIB"pure_quanta"
CDS_LOCATION"R1798"
$SEC"1"
CDS_SEC"1";
"B"
$PN"2"20;
"A"
$PN"1"177;
%"Q_RES"
"1","(-13325,-1375)","0","pure_quanta","I21";
;
PART_NUMBER"CS00002JB13"
TOLERANCE"5%"
MATERIAL"CHIP"
VALUE"0"
$LOCATION"R3776"
PACK_TYPE"0402LF"
WATTAGE"1/16W"
CDS_LIB"pure_quanta"
CDS_LOCATION"R3776"
$SEC"1"
CDS_SEC"1";
"B"
$PN"2"15;
"A"
$PN"1"176;
%"Q_RES"
"1","(-13300,-675)","0","pure_quanta","I22";
;
PART_NUMBER"CS03322FB03"
VALUE"33.2"
MATERIAL"CHIP"
TOLERANCE"1%"
$LOCATION"R2417"
CDS_LIB"pure_quanta"
PACK_TYPE"0402LF"
WATTAGE"1/16W"
CDS_LOCATION"R2417"
$SEC"1"
CDS_SEC"1";
"B"
$PN"2"157;
"A"
$PN"1"173;
%"Q_RES"
"1","(-13300,-725)","0","pure_quanta","I23";
;
PART_NUMBER"CS03322FB03"
MATERIAL"CHIP"
TOLERANCE"1%"
VALUE"33.2"
$LOCATION"R2418"
WATTAGE"1/16W"
PACK_TYPE"0402LF"
CDS_LIB"pure_quanta"
CDS_LOCATION"R2418"
$SEC"1"
CDS_SEC"1";
"B"
$PN"2"13;
"A"
$PN"1"169;
%"Q_RES"
"1","(-13300,-625)","0","pure_quanta","I24";
;
PART_NUMBER"CS00002JB13"
MATERIAL"CHIP"
VALUE"0"
TOLERANCE"5%"
$LOCATION"R2416"
CDS_LIB"pure_quanta"
PACK_TYPE"0402LF"
WATTAGE"1/16W"
CDS_LOCATION"R2416"
$SEC"1"
CDS_SEC"1";
"B"
$PN"2"158;
"A"
$PN"1"172;
%"Q_RES"
"1","(-13300,-575)","0","pure_quanta","I25";
;
PART_NUMBER"CS00002JB13"
MATERIAL"CHIP"
VALUE"0"
TOLERANCE"5%"
$LOCATION"R2415"
CDS_LIB"pure_quanta"
PACK_TYPE"0402LF"
WATTAGE"1/16W"
CDS_LOCATION"R2415"
$SEC"1"
CDS_SEC"1";
"B"
$PN"2"12;
"A"
$PN"1"171;
%"Q_RES"
"1","(-13075,-1125)","0","pure_quanta","I26";
;
PART_NUMBER"CS00002JB13"
VALUE"0"
MATERIAL"CHIP"
TOLERANCE"5%"
$LOCATION"R1815"
CDS_LIB"pure_quanta"
WATTAGE"1/16W"
PACK_TYPE"0402LF"
CDS_LOCATION"R1815"
$SEC"1"
CDS_SEC"1";
"B"
$PN"2"14;
"A"
$PN"1"175;
%"Q_RES"
"1","(-13075,-975)","0","pure_quanta","I27";
;
PART_NUMBER"CS00002JB13"
MATERIAL"CHIP"
VALUE"0"
TOLERANCE"5%"
$LOCATION"R1816"
WATTAGE"1/16W"
PACK_TYPE"0402LF"
CDS_LIB"pure_quanta"
CDS_LOCATION"R1816"
$SEC"1"
CDS_SEC"1";
"B"
$PN"2"164;
"A"
$PN"1"174;
%"Q_RES"
"1","(-13075,-925)","0","pure_quanta","I28";
;
PART_NUMBER"CS03322FB03"
MATERIAL"CHIP"
VALUE"33.2"
TOLERANCE"1%"
LOCATION"R4087"
CDS_LIB"pure_quanta"
WATTAGE"1/16W"
PACK_TYPE"0402LF"
$SEC"1"
CDS_SEC"1";
"B"
$PN"2"21;
"A"
$PN"1"170;
%"UNIVERSAL_GND"
"1","(-11275,-2675)","0","logical_power","I40";
;
CDS_LIB"logical_power"
HDL_POWER"GND";
"A"5;
%"UNIVERSAL_GND"
"1","(-9550,-2600)","0","logical_power","I41";
;
HDL_POWER"GND"
CDS_LIB"logical_power";
"A"6;
%"Q_RES"
"1","(-7875,-2225)","0","pure_quanta","I48";
;
PART_NUMBER"CS00002JB13"
MATERIAL"EMPTY"
VALUE"0"
$LOCATION"R3302"
CDS_LIB"pure_quanta"
PACK_TYPE"0402LF"
TOLERANCE"5%"
WATTAGE"1/16W"
CDS_LOCATION"R3302"
$SEC"1"
CDS_SEC"1";
"B"
$PN"2"132;
"A"
$PN"1"136;
%"Q_RES"
"1","(-7875,-2175)","0","pure_quanta","I49";
;
PART_NUMBER"CS00002JB13"
WATTAGE"1/16W"
TOLERANCE"5%"
VALUE"0"
PACK_TYPE"0402LF"
MATERIAL"EMPTY"
$LOCATION"R3254"
CDS_LIB"pure_quanta"
CDS_LOCATION"R3254"
$SEC"1"
CDS_SEC"1";
"B"
$PN"2"133;
"A"
$PN"1"138;
%"Q_RES"
"1","(-7800,-775)","0","pure_quanta","I57";
;
PART_NUMBER"CS00002JB13"
MATERIAL"CHIP"
VALUE"0"
WATTAGE"1/16W"
$LOCATION"R4720"
CDS_LIB"pure_quanta"
PACK_TYPE"0402LF"
TOLERANCE"5%"
CDS_LOCATION"R4720"
$SEC"1"
CDS_SEC"1";
"B"
$PN"2"134;
"A"
$PN"1"152;
%"Q_RES"
"1","(-7800,-725)","0","pure_quanta","I58";
;
PART_NUMBER"CS00002JB13"
MATERIAL"CHIP"
TOLERANCE"5%"
VALUE"0"
PACK_TYPE"0402LF"
WATTAGE"1/16W"
$LOCATION"R2994"
CDS_LIB"pure_quanta"
CDS_LOCATION"R2994"
$SEC"1"
CDS_SEC"1";
"B"
$PN"2"135;
"A"
$PN"1"153;
%"UNIVERSAL_GND"
"1","(-14975,1950)","0","logical_power","I81";
;
HDL_POWER"GND"
CDS_LIB"logical_power";
"A"7;
%"Q_CAP"
"1","(-14975,2175)","0","pure_quanta","I82";
;
PART_NUMBER"CH622KMEB01"
TOLERANCE"20%"
VOLTAGE"4V"
PACK_TYPE"C0402"
MATERIAL"X6S"
VALUE"22UF"
LOCATION"C1302"
CDS_LIB"pure_quanta"
$SEC"1"
CDS_SEC"1";
"B"
$PN"2"7;
"A"
$PN"1"1;
%"UNIVERSAL_POWER"
"1","(-14975,2525)","0","logical_power","I83";
;
HDL_POWER"PVNN_TERM_CPU0"
CDS_LIB"logical_power";
"A"1;
%"Q_RES"
"1","(-14625,2375)","0","pure_quanta","I84";
;
PART_NUMBER"CS00002JB13"
WATTAGE"1/16W"
TOLERANCE"5%"
MATERIAL"CHIP"
VALUE"0"
PACK_TYPE"0402LF"
$LOCATION"R142"
CDS_LIB"pure_quanta"
CDS_LOCATION"R142"
$SEC"1"
CDS_SEC"1";
"B"
$PN"2"129;
"A"
$PN"1"1;
%"Q_RES"
"1","(-13300,-275)","0","pure_quanta","I85";
;
PART_NUMBER"CS00002JB13"
VALUE"0"
TOLERANCE"5%"
MATERIAL"CHIP"
$LOCATION"R2414"
CDS_LIB"pure_quanta"
WATTAGE"1/16W"
PACK_TYPE"0402LF"
CDS_LOCATION"R2414"
$SEC"1"
CDS_SEC"1";
"B"
$PN"2"11;
"A"
$PN"1"124;
%"Q_RES"
"1","(-13300,-225)","0","pure_quanta","I86";
;
PART_NUMBER"CS00002JB13"
TOLERANCE"5%"
VALUE"0"
MATERIAL"CHIP"
$LOCATION"R2413"
CDS_LIB"pure_quanta"
WATTAGE"1/16W"
PACK_TYPE"0402LF"
CDS_LOCATION"R2413"
$SEC"1"
CDS_SEC"1";
"B"
$PN"2"113;
"A"
$PN"1"128;
%"Q_RES"
"1","(-13275,75)","0","pure_quanta","I87";
;
PART_NUMBER"CS03322FB03"
MATERIAL"CHIP"
TOLERANCE"1%"
VALUE"33.2"
$LOCATION"R4508"
CDS_LIB"pure_quanta"
PACK_TYPE"0402LF"
WATTAGE"1/16W"
CDS_LOCATION"R4508"
$SEC"1"
CDS_SEC"1";
"B"
$PN"2"105;
"A"
$PN"1"22;
%"Q_RES"
"1","(-13275,25)","0","pure_quanta","I88";
;
PART_NUMBER"CS03322FB03"
MATERIAL"CHIP"
VALUE"33.2"
TOLERANCE"1%"
$LOCATION"R4509"
CDS_LIB"pure_quanta"
PACK_TYPE"0402LF"
WATTAGE"1/16W"
CDS_LOCATION"R4509"
$SEC"1"
CDS_SEC"1";
"B"
$PN"2"107;
"A"
$PN"1"120;
%"Q_RES"
"1","(-13275,125)","0","pure_quanta","I89";
;
PART_NUMBER"CS03322FB03"
MATERIAL"CHIP"
VALUE"33.2"
TOLERANCE"1%"
$LOCATION"R4507"
WATTAGE"1/16W"
PACK_TYPE"0402LF"
CDS_LIB"pure_quanta"
CDS_LOCATION"R4507"
$SEC"1"
CDS_SEC"1";
"B"
$PN"2"23;
"A"
$PN"1"125;
%"Q_RES"
"1","(-13275,175)","0","pure_quanta","I90";
;
PART_NUMBER"CS03322FB03"
MATERIAL"CHIP"
TOLERANCE"1%"
VALUE"33.2"
$LOCATION"R4506"
WATTAGE"1/16W"
PACK_TYPE"0402LF"
CDS_LIB"pure_quanta"
CDS_LOCATION"R4506"
$SEC"1"
CDS_SEC"1";
"B"
$PN"2"104;
"A"
$PN"1"116;
%"Q_RES"
"1","(-13275,725)","0","pure_quanta","I91";
;
PART_NUMBER"CS01002FB07"
MATERIAL"CHIP"
VALUE"10"
$LOCATION"R4535"
WATTAGE"1/16W"
TOLERANCE"1%"
PACK_TYPE"0402LF"
CDS_LIB"pure_quanta"
CDS_LOCATION"R4535"
$SEC"1"
CDS_SEC"1";
"B"
$PN"2"94;
"A"
$PN"1"118;
%"Q_RES"
"1","(-13275,675)","0","pure_quanta","I92";
;
PART_NUMBER"CS01002FB07"
TOLERANCE"1%"
VALUE"10"
MATERIAL"CHIP"
$LOCATION"R4536"
WATTAGE"1/16W"
PACK_TYPE"0402LF"
CDS_LIB"pure_quanta"
CDS_LOCATION"R4536"
$SEC"1"
CDS_SEC"1";
"B"
$PN"2"101;
"A"
$PN"1"119;
%"Q_RES"
"1","(-13275,875)","0","pure_quanta","I93";
;
PART_NUMBER"CS03322FB03"
MATERIAL"CHIP"
VALUE"33.2"
TOLERANCE"1%"
$LOCATION"R2425"
WATTAGE"1/16W"
PACK_TYPE"0402LF"
CDS_LIB"pure_quanta"
CDS_LOCATION"R2425"
$SEC"1"
CDS_SEC"1";
"B"
$PN"2"93;
"A"
$PN"1"121;
%"Q_RES"
"1","(-13275,825)","0","pure_quanta","I94";
;
PART_NUMBER"CS03322FB03"
MATERIAL"CHIP"
TOLERANCE"1%"
VALUE"33.2"
$LOCATION"R3858"
WATTAGE"1/16W"
PACK_TYPE"0402LF"
CDS_LIB"pure_quanta"
CDS_LOCATION"R3858"
$SEC"1"
CDS_SEC"1";
"B"
$PN"2"102;
"A"
$PN"1"117;
%"Q_RES"
"1","(-13275,1125)","0","pure_quanta","I95";
;
PART_NUMBER"CS03322FB03"
TOLERANCE"1%"
MATERIAL"CHIP"
VALUE"33.2"
$LOCATION"R2422"
CDS_LIB"pure_quanta"
PACK_TYPE"0402LF"
WATTAGE"1/16W"
CDS_LOCATION"R2422"
$SEC"1"
CDS_SEC"1";
"B"
$PN"2"88;
"A"
$PN"1"114;
%"Q_RES"
"1","(-13275,1025)","0","pure_quanta","I96";
;
PART_NUMBER"CS03322FB03"
VALUE"33.2"
MATERIAL"CHIP"
TOLERANCE"1%"
$LOCATION"R2424"
PACK_TYPE"0402LF"
WATTAGE"1/16W"
CDS_LIB"pure_quanta"
CDS_LOCATION"R2424"
$SEC"1"
CDS_SEC"1";
"B"
$PN"2"90;
"A"
$PN"1"126;
%"Q_RES"
"1","(-13275,1075)","0","pure_quanta","I97";
;
PART_NUMBER"CS03322FB03"
VALUE"33.2"
TOLERANCE"1%"
MATERIAL"CHIP"
$LOCATION"R2423"
PACK_TYPE"0402LF"
WATTAGE"1/16W"
CDS_LIB"pure_quanta"
CDS_LOCATION"R2423"
$SEC"1"
CDS_SEC"1";
"B"
$PN"2"89;
"A"
$PN"1"10;
%"Q_RES"
"1","(-13275,1225)","0","pure_quanta","I98";
;
PART_NUMBER"CS03322FB03"
VALUE"33.2"
TOLERANCE"1%"
MATERIAL"CHIP"
$LOCATION"R2420"
WATTAGE"1/16W"
PACK_TYPE"0402LF"
CDS_LIB"pure_quanta"
CDS_LOCATION"R2420"
$SEC"1"
CDS_SEC"1";
"B"
$PN"2"86;
"A"
$PN"1"122;
%"Q_RES"
"1","(-13275,1175)","0","pure_quanta","I99";
;
PART_NUMBER"CS03322FB03"
VALUE"33.2"
MATERIAL"CHIP"
TOLERANCE"1%"
$LOCATION"R2421"
CDS_LIB"pure_quanta"
PACK_TYPE"0402LF"
WATTAGE"1/16W"
CDS_LOCATION"R2421"
$SEC"1"
CDS_SEC"1";
"B"
$PN"2"87;
"A"
$PN"1"115;
END.
